# T6G (Grand Teton) — schematic netlist excerpt (pin names and nets, part order shuffled) for the footprints in the layout excerpt that follows; sources: Cadence DE-HDL packaged netlist, KiCad conversion of 04192023_DAF0TMB3IC0_F0TG_MB_C_brd_V02_OCP.brd

R84  Q_RES  100K 1% CHIP  pkg 0402LF  page 132 : A = RMII_BMC_OCP_TXD_1 ; B = GND
C2395  Q_CAP  22UF 4V 20% X6S  pkg C0402  page 73 : A = PVDDCR_CPU1_P1 ; B = GND

(kicad_pcb
	(version 20260206)
	(generator "pcbnew")
	(generator_version "10.0")
	(general
		(thickness 1.6)
		(legacy_teardrops no)
	)
	(paper "A4")
	(title_block
		(title "04192023_DAF0TMB3IC0_F0TG_MB_C_brd_V02_OCP.brd")
		(comment 1 "Grand Teton / footprints 8216-8217 of 8354")
	)
	(layers
		(0 "F.Cu" signal "TOP")
		(4 "In1.Cu" signal "GND")
		(6 "In2.Cu" signal "IN1")
		(8 "In3.Cu" signal "GND1")
		(10 "In4.Cu" signal "IN2")
		(12 "In5.Cu" signal "GND2")
		(14 "In6.Cu" signal "IN3")
		(16 "In7.Cu" signal "GND3")
		(18 "In8.Cu" signal "VCC")
		(20 "In9.Cu" signal "VCC1")
		(22 "In10.Cu" signal "GND4")
		(24 "In11.Cu" signal "IN4")
		(26 "In12.Cu" signal "GND5")
		(28 "In13.Cu" signal "IN5")
		(30 "In14.Cu" signal "GND6")
		(32 "In15.Cu" signal "IN6")
		(34 "In16.Cu" signal "GND7")
		(2 "B.Cu" signal "BOTTOM")
		(9 "F.Adhes" user "F.Adhesive")
		(11 "B.Adhes" user "B.Adhesive")
		(13 "F.Paste" user "Package Geometry/Pastemask Top")
		(15 "B.Paste" user "Package Geometry/Pastemask Bottom")
		(5 "F.SilkS" user "Ref Des/Silkscreen Top")
		(7 "B.SilkS" user "Ref Des/Silkscreen Bottom")
		(1 "F.Mask" user "Board Geometry/Soldermask Top")
		(3 "B.Mask" user "Board Geometry/Soldermask Bottom")
		(17 "Dwgs.User" user "User.Drawings")
		(19 "Cmts.User" user "User.Comments")
		(21 "Eco1.User" user "User.Eco1")
		(23 "Eco2.User" user "User.Eco2")
		(25 "Edge.Cuts" user "Board Geometry/Outline")
		(27 "Margin" user)
		(31 "F.CrtYd" user "Package Geometry/Place Bound Top")
		(29 "B.CrtYd" user "Package Geometry/Place Bound Bottom")
		(35 "F.Fab" user "Ref Des/Assembly Top")
		(33 "B.Fab" user "Ref Des/Assembly Bottom")
	)
	(footprint ""
		(layer "B.Cu")
		(at 215.514428 -74.055986 180)
		(property "Reference" "R84"
			(at 0 0 0)
			(layer "B.SilkS")
			(hide yes)
			(effects
				(font
					(size 1.27 1.27)
				)
				(justify mirror)
			)
		)
		(property "Value" ""
			(at 0 0 0)
			(layer "B.Fab")
			(effects
				(font
					(size 1.27 1.27)
				)
				(justify mirror)
			)
		)
		(duplicate_pad_numbers_are_jumpers no)
		(fp_line
			(start 0.7874 0.4064)
			(end 0.7874 -0.4064)
			(stroke
				(width 0.1524)
				(type default)
			)
			(layer "B.SilkS")
		)
		(fp_line
			(start 0.7874 -0.4064)
			(end -0.7874 -0.4064)
			(stroke
				(width 0.1524)
				(type default)
			)
			(layer "B.SilkS")
		)
		(fp_line
			(start -0.7874 0.4064)
			(end 0.7874 0.4064)
			(stroke
				(width 0.1524)
				(type default)
			)
			(layer "B.SilkS")
		)
		(fp_line
			(start -0.7874 -0.4064)
			(end -0.7874 0.4064)
			(stroke
				(width 0.1524)
				(type default)
			)
			(layer "B.SilkS")
		)
		(fp_line
			(start 0.67945 0.3048)
			(end 0.67945 -0.305054)
			(stroke
				(width 0.1)
				(type default)
			)
			(layer "B.Fab")
		)
		(fp_line
			(start 0.67945 -0.305054)
			(end 0.12065 -0.305054)
			(stroke
				(width 0.1)
				(type default)
			)
			(layer "B.Fab")
		)
		(fp_line
			(start 0.12065 0.3048)
			(end 0.67945 0.3048)
			(stroke
				(width 0.1)
				(type default)
			)
			(layer "B.Fab")
		)
		(fp_line
			(start 0.12065 0.2794)
			(end 0.12065 0.3048)
			(stroke
				(width 0.1)
				(type default)
			)
			(layer "B.Fab")
		)
		(fp_line
			(start 0.12065 -0.2794)
			(end -0.12065 -0.2794)
			(stroke
				(width 0.1)
				(type default)
			)
			(layer "B.Fab")
		)
		(fp_line
			(start 0.12065 -0.305054)
			(end 0.12065 -0.2794)
			(stroke
				(width 0.1)
				(type default)
			)
			(layer "B.Fab")
		)
		(fp_line
			(start -0.120396 0.3048)
			(end -0.120396 0.2794)
			(stroke
				(width 0.1)
				(type default)
			)
			(layer "B.Fab")
		)
		(fp_line
			(start -0.120396 0.2794)
			(end 0.12065 0.2794)
			(stroke
				(width 0.1)
				(type default)
			)
			(layer "B.Fab")
		)
		(fp_line
			(start -0.12065 -0.2794)
			(end -0.12065 -0.3048)
			(stroke
				(width 0.1)
				(type default)
			)
			(layer "B.Fab")
		)
		(fp_line
			(start -0.12065 -0.3048)
			(end -0.67945 -0.3048)
			(stroke
				(width 0.1)
				(type default)
			)
			(layer "B.Fab")
		)
		(fp_line
			(start -0.67945 0.3048)
			(end -0.120396 0.3048)
			(stroke
				(width 0.1)
				(type default)
			)
			(layer "B.Fab")
		)
		(fp_line
			(start -0.67945 -0.3048)
			(end -0.67945 0.3048)
			(stroke
				(width 0.1)
				(type default)
			)
			(layer "B.Fab")
		)
		(pad "1" smd circle
			(at 0.40005 0)
			(size 0 0)
			(layers "B.Cu" "B.Mask" "B.Paste")
			(net "RMII_BMC_OCP_TXD_1")
		)
		(pad "2" smd circle
			(at -0.40005 0)
			(size 0 0)
			(layers "B.Cu" "B.Mask" "B.Paste")
			(net "GND")
		)
	)
	(footprint ""
		(layer "B.Cu")
		(at 105.605834 -272.284952)
		(property "Reference" "C2395"
			(at 0 0 0)
			(layer "B.SilkS")
			(hide yes)
			(effects
				(font
					(size 1.27 1.27)
				)
				(justify mirror)
			)
		)
		(property "Value" ""
			(at 0 0 0)
			(layer "B.Fab")
			(effects
				(font
					(size 1.27 1.27)
				)
				(justify mirror)
			)
		)
		(duplicate_pad_numbers_are_jumpers no)
		(fp_line
			(start -0.7874 -0.4064)
			(end -0.7874 0.4064)
			(stroke
				(width 0.1524)
				(type default)
			)
			(layer "B.SilkS")
		)
		(fp_line
			(start -0.7874 0.4064)
			(end 0.7874 0.4064)
			(stroke
				(width 0.1524)
				(type default)
			)
			(layer "B.SilkS")
		)
		(fp_line
			(start 0.7874 -0.4064)
			(end -0.7874 -0.4064)
			(stroke
				(width 0.1524)
				(type default)
			)
			(layer "B.SilkS")
		)
		(fp_line
			(start 0.7874 0.4064)
			(end 0.7874 -0.4064)
			(stroke
				(width 0.1524)
				(type default)
			)
			(layer "B.SilkS")
		)
		(fp_line
			(start -0.67945 -0.3048)
			(end -0.67945 0.3048)
			(stroke
				(width 0.1)
				(type default)
			)
			(layer "B.Fab")
		)
		(fp_line
			(start -0.67945 0.3048)
			(end -0.120396 0.3048)
			(stroke
				(width 0.1)
				(type default)
			)
			(layer "B.Fab")
		)
		(fp_line
			(start -0.12065 -0.3048)
			(end -0.67945 -0.3048)
			(stroke
				(width 0.1)
				(type default)
			)
			(layer "B.Fab")
		)
		(fp_line
			(start -0.12065 -0.2794)
			(end -0.12065 -0.3048)
			(stroke
				(width 0.1)
				(type default)
			)
			(layer "B.Fab")
		)
		(fp_line
			(start -0.120396 0.2794)
			(end 0.12065 0.2794)
			(stroke
				(width 0.1)
				(type default)
			)
			(layer "B.Fab")
		)
		(fp_line
			(start -0.120396 0.3048)
			(end -0.120396 0.2794)
			(stroke
				(width 0.1)
				(type default)
			)
			(layer "B.Fab")
		)
		(fp_line
			(start 0.12065 -0.305054)
			(end 0.12065 -0.2794)
			(stroke
				(width 0.1)
				(type default)
			)
			(layer "B.Fab")
		)
		(fp_line
			(start 0.12065 -0.2794)
			(end -0.12065 -0.2794)
			(stroke
				(width 0.1)
				(type default)
			)
			(layer "B.Fab")
		)
		(fp_line
			(start 0.12065 0.2794)
			(end 0.12065 0.3048)
			(stroke
				(width 0.1)
				(type default)
			)
			(layer "B.Fab")
		)
		(fp_line
			(start 0.12065 0.3048)
			(end 0.67945 0.3048)
			(stroke
				(width 0.1)
				(type default)
			)
			(layer "B.Fab")
		)
		(fp_line
			(start 0.67945 -0.305054)
			(end 0.12065 -0.305054)
			(stroke
				(width 0.1)
				(type default)
			)
			(layer "B.Fab")
		)
		(fp_line
			(start 0.67945 0.3048)
			(end 0.67945 -0.305054)
			(stroke
				(width 0.1)
				(type default)
			)
			(layer "B.Fab")
		)
		(pad "1" smd circle
			(at 0.40005 0 180)
			(size 0 0)
			(layers "B.Cu" "B.Mask" "B.Paste")
			(net "PVDDCR_CPU1_P1")
		)
		(pad "2" smd circle
			(at -0.40005 0 180)
			(size 0 0)
			(layers "B.Cu" "B.Mask" "B.Paste")
			(net "GND")
		)
	)
)
